# S9S_MB_2U (Grand Teton) — schematic netlist excerpt (pin names and nets, part order shuffled) for the footprints in the layout excerpt that follows; sources: Cadence DE-HDL packaged netlist, KiCad conversion of 03242023_DA0F0TMBIJ0_F0T_Motherboard_J_brd_V01_OCP.brd

PC1789  Q_CAP  0.1UF 25V 10% EMPTY  pkg 0402  page 305 : A = P12V_AUX ; B = GND

Q77  MOSFET_NCH_DUAL  PJT138K IC  pkg SOT363XD  page 252
  S1  = GND
  G1  = RST_RSMRST_PLD_R_N
  D2  = LED_FM_PCH_SLP_S4_N_D
  S2  = GND
  G2  = FM_PCH_SLP_S4_N
  D1  = LED_RST_RSMRST_PLD_R_N_D

(kicad_pcb
	(version 20260206)
	(generator "pcbnew")
	(generator_version "10.0")
	(general
		(thickness 1.6)
		(legacy_teardrops no)
	)
	(paper "A4")
	(title_block
		(title "03242023_DA0F0TMBIJ0_F0T_Motherboard_J_brd_V01_OCP.brd")
		(comment 1 "Grand Teton / footprints 2839-2840 of 6105")
	)
	(layers
		(0 "F.Cu" signal "TOP")
		(4 "In1.Cu" signal "GND")
		(6 "In2.Cu" signal "IN1")
		(8 "In3.Cu" signal "GND1")
		(10 "In4.Cu" signal "IN2")
		(12 "In5.Cu" signal "GND2")
		(14 "In6.Cu" signal "IN3")
		(16 "In7.Cu" signal "GND3")
		(18 "In8.Cu" signal "VCC")
		(20 "In9.Cu" signal "VCC1")
		(22 "In10.Cu" signal "GND4")
		(24 "In11.Cu" signal "IN4")
		(26 "In12.Cu" signal "GND5")
		(28 "In13.Cu" signal "IN5")
		(30 "In14.Cu" signal "GND6")
		(32 "In15.Cu" signal "IN6")
		(34 "In16.Cu" signal "GND7")
		(2 "B.Cu" signal "BOTTOM")
		(9 "F.Adhes" user "F.Adhesive")
		(11 "B.Adhes" user "B.Adhesive")
		(13 "F.Paste" user "Package Geometry/Pastemask Top")
		(15 "B.Paste" user "Package Geometry/Pastemask Bottom")
		(5 "F.SilkS" user "Ref Des/Silkscreen Top")
		(7 "B.SilkS" user "Ref Des/Silkscreen Bottom")
		(1 "F.Mask" user "Board Geometry/Soldermask Top")
		(3 "B.Mask" user "Board Geometry/Soldermask Bottom")
		(17 "Dwgs.User" user "User.Drawings")
		(19 "Cmts.User" user "User.Comments")
		(21 "Eco1.User" user "User.Eco1")
		(23 "Eco2.User" user "User.Eco2")
		(25 "Edge.Cuts" user "Board Geometry/Outline")
		(27 "Margin" user)
		(31 "F.CrtYd" user "Package Geometry/Place Bound Top")
		(29 "B.CrtYd" user "Package Geometry/Place Bound Bottom")
		(35 "F.Fab" user "Ref Des/Assembly Top")
		(33 "B.Fab" user "Ref Des/Assembly Bottom")
	)
	(footprint ""
		(layer "F.Cu")
		(at 288.580068 -395.046454 180)
		(property "Reference" "PC1789"
			(at 0 0 180)
			(layer "F.SilkS")
			(hide yes)
			(effects
				(font
					(size 1.27 1.27)
				)
			)
		)
		(property "Value" ""
			(at 0 0 180)
			(layer "F.Fab")
			(effects
				(font
					(size 1.27 1.27)
				)
			)
		)
		(duplicate_pad_numbers_are_jumpers no)
		(fp_line
			(start 0.7874 0.4064)
			(end -0.7874 0.4064)
			(stroke
				(width 0.1524)
				(type default)
			)
			(layer "F.SilkS")
		)
		(fp_line
			(start 0.7874 -0.4064)
			(end 0.7874 0.4064)
			(stroke
				(width 0.1524)
				(type default)
			)
			(layer "F.SilkS")
		)
		(fp_line
			(start -0.7874 0.4064)
			(end -0.7874 -0.4064)
			(stroke
				(width 0.1524)
				(type default)
			)
			(layer "F.SilkS")
		)
		(fp_line
			(start -0.7874 -0.4064)
			(end 0.7874 -0.4064)
			(stroke
				(width 0.1524)
				(type default)
			)
			(layer "F.SilkS")
		)
		(fp_line
			(start 0.67945 0.3048)
			(end 0.120396 0.3048)
			(stroke
				(width 0.1)
				(type default)
			)
			(layer "F.Fab")
		)
		(fp_line
			(start 0.67945 -0.3048)
			(end 0.67945 0.3048)
			(stroke
				(width 0.1)
				(type default)
			)
			(layer "F.Fab")
		)
		(fp_line
			(start 0.12065 -0.2794)
			(end 0.12065 -0.3048)
			(stroke
				(width 0.1)
				(type default)
			)
			(layer "F.Fab")
		)
		(fp_line
			(start 0.12065 -0.3048)
			(end 0.67945 -0.3048)
			(stroke
				(width 0.1)
				(type default)
			)
			(layer "F.Fab")
		)
		(fp_line
			(start 0.120396 0.3048)
			(end 0.120396 0.2794)
			(stroke
				(width 0.1)
				(type default)
			)
			(layer "F.Fab")
		)
		(fp_line
			(start 0.120396 0.2794)
			(end -0.12065 0.2794)
			(stroke
				(width 0.1)
				(type default)
			)
			(layer "F.Fab")
		)
		(fp_line
			(start -0.12065 0.3048)
			(end -0.67945 0.3048)
			(stroke
				(width 0.1)
				(type default)
			)
			(layer "F.Fab")
		)
		(fp_line
			(start -0.12065 0.2794)
			(end -0.12065 0.3048)
			(stroke
				(width 0.1)
				(type default)
			)
			(layer "F.Fab")
		)
		(fp_line
			(start -0.12065 -0.2794)
			(end 0.12065 -0.2794)
			(stroke
				(width 0.1)
				(type default)
			)
			(layer "F.Fab")
		)
		(fp_line
			(start -0.12065 -0.305054)
			(end -0.12065 -0.2794)
			(stroke
				(width 0.1)
				(type default)
			)
			(layer "F.Fab")
		)
		(fp_line
			(start -0.67945 0.3048)
			(end -0.67945 -0.305054)
			(stroke
				(width 0.1)
				(type default)
			)
			(layer "F.Fab")
		)
		(fp_line
			(start -0.67945 -0.305054)
			(end -0.12065 -0.305054)
			(stroke
				(width 0.1)
				(type default)
			)
			(layer "F.Fab")
		)
		(pad "1" smd circle
			(at -0.40005 0 180)
			(size 0 0)
			(layers "F.Cu" "F.Mask" "F.Paste")
			(net "P12V_AUX")
		)
		(pad "2" smd circle
			(at 0.40005 0 180)
			(size 0 0)
			(layers "F.Cu" "F.Mask" "F.Paste")
			(net "GND")
		)
	)
	(footprint ""
		(layer "F.Cu")
		(at 108.006388 -102.943152)
		(property "Reference" "Q77"
			(at -1.803908 -3.540506 0)
			(unlocked yes)
			(layer "F.SilkS")
			(effects
				(font
					(size 0.7874 0.5842)
					(thickness 0.1524)
				)
				(justify left)
			)
		)
		(property "Value" ""
			(at 0 0 0)
			(layer "F.Fab")
			(effects
				(font
					(size 1.27 1.27)
				)
			)
		)
		(duplicate_pad_numbers_are_jumpers no)
		(fp_line
			(start -1.332738 -1.100074)
			(end -0.4826 -1.100074)
			(stroke
				(width 0.1524)
				(type default)
			)
			(layer "F.SilkS")
		)
		(fp_line
			(start -1.332738 1.100074)
			(end -1.332738 -1.100074)
			(stroke
				(width 0.1524)
				(type default)
			)
			(layer "F.SilkS")
		)
		(fp_line
			(start -0.4826 -1.100074)
			(end 0 -0.541274)
			(stroke
				(width 0.1524)
				(type default)
			)
			(layer "F.SilkS")
		)
		(fp_line
			(start 0 -0.541274)
			(end 0.4826 -1.100074)
			(stroke
				(width 0.1524)
				(type default)
			)
			(layer "F.SilkS")
		)
		(fp_line
			(start 0.4826 -1.100074)
			(end 1.332738 -1.100074)
			(stroke
				(width 0.1524)
				(type default)
			)
			(layer "F.SilkS")
		)
		(fp_line
			(start 1.332738 -1.100074)
			(end 1.332738 1.100074)
			(stroke
				(width 0.1524)
				(type default)
			)
			(layer "F.SilkS")
		)
		(fp_line
			(start 1.332738 1.100074)
			(end -1.332738 1.100074)
			(stroke
				(width 0.1524)
				(type default)
			)
			(layer "F.SilkS")
		)
		(fp_poly
			(pts
				(xy -0.60325 -2.019808) (xy -0.954278 -1.317752) (xy -1.305306 -2.019808)
			)
			(stroke
				(width 0)
				(type default)
			)
			(fill yes)
			(layer "F.SilkS")
		)
		(fp_line
			(start -0.674878 -1.100074)
			(end 0.674878 -1.100074)
			(stroke
				(width 0.1)
				(type default)
			)
			(layer "F.Fab")
		)
		(fp_line
			(start -0.674878 1.100074)
			(end -0.674878 -1.100074)
			(stroke
				(width 0.1)
				(type default)
			)
			(layer "F.Fab")
		)
		(fp_line
			(start 0.674878 -1.100074)
			(end 0.674878 1.100074)
			(stroke
				(width 0.1)
				(type default)
			)
			(layer "F.Fab")
		)
		(fp_line
			(start 0.674878 1.100074)
			(end -0.674878 1.100074)
			(stroke
				(width 0.1)
				(type default)
			)
			(layer "F.Fab")
		)
		(fp_poly
			(pts
				(xy -2.2352 -0.298958) (xy -2.2352 -1.001014) (xy -1.533144 -0.649986)
			)
			(stroke
				(width 0)
				(type default)
			)
			(fill yes)
			(layer "F.Fab")
		)
		(pad "1" smd rect
			(at -0.94996 -0.649986 90)
			(size 0.4318 0.508)
			(layers "F.Cu" "F.Mask" "F.Paste")
			(net "GND")
		)
		(pad "2" smd rect
			(at -0.94996 0 90)
			(size 0.4318 0.508)
			(layers "F.Cu" "F.Mask" "F.Paste")
			(net "RST_RSMRST_PLD_R_N")
		)
		(pad "3" smd rect
			(at -0.94996 0.649986 90)
			(size 0.4318 0.508)
			(layers "F.Cu" "F.Mask" "F.Paste")
			(net "LED_FM_PCH_SLP_S4_N_D")
		)
		(pad "4" smd rect
			(at 0.94996 0.649986 90)
			(size 0.4318 0.508)
			(layers "F.Cu" "F.Mask" "F.Paste")
			(net "GND")
		)
		(pad "5" smd rect
			(at 0.94996 0 90)
			(size 0.4318 0.508)
			(layers "F.Cu" "F.Mask" "F.Paste")
			(net "FM_PCH_SLP_S4_N")
		)
		(pad "6" smd rect
			(at 0.94996 -0.649986 90)
			(size 0.4318 0.508)
			(layers "F.Cu" "F.Mask" "F.Paste")
			(net "LED_RST_RSMRST_PLD_R_N_D")
		)
	)
)
